(kicad_pcb
	(version 20260206)
	(generator "pcbnew")
	(generator_version "10.0")
	(general
		(thickness 1.6)
		(legacy_teardrops no)
	)
	(paper "A4")
	(title_block
		(title "03242023_DA0F0TMBIJ0_F0T_Motherboard_J_brd_V01_OCP.brd")
		(comment 1 "Grand Teton / footprints 6024-6030 of 6105")
	)
	(layers
		(0 "F.Cu" signal "TOP")
		(4 "In1.Cu" signal "GND")
		(6 "In2.Cu" signal "IN1")
		(8 "In3.Cu" signal "GND1")
		(10 "In4.Cu" signal "IN2")
		(12 "In5.Cu" signal "GND2")
		(14 "In6.Cu" signal "IN3")
		(16 "In7.Cu" signal "GND3")
		(18 "In8.Cu" signal "VCC")
		(20 "In9.Cu" signal "VCC1")
		(22 "In10.Cu" signal "GND4")
		(24 "In11.Cu" signal "IN4")
		(26 "In12.Cu" signal "GND5")
		(28 "In13.Cu" signal "IN5")
		(30 "In14.Cu" signal "GND6")
		(32 "In15.Cu" signal "IN6")
		(34 "In16.Cu" signal "GND7")
		(2 "B.Cu" signal "BOTTOM")
		(9 "F.Adhes" user "F.Adhesive")
		(11 "B.Adhes" user "B.Adhesive")
		(13 "F.Paste" user "Package Geometry/Pastemask Top")
		(15 "B.Paste" user "Package Geometry/Pastemask Bottom")
		(5 "F.SilkS" user "Ref Des/Silkscreen Top")
		(7 "B.SilkS" user "Ref Des/Silkscreen Bottom")
		(1 "F.Mask" user "Board Geometry/Soldermask Top")
		(3 "B.Mask" user "Board Geometry/Soldermask Bottom")
		(17 "Dwgs.User" user "User.Drawings")
		(19 "Cmts.User" user "User.Comments")
		(21 "Eco1.User" user "User.Eco1")
		(23 "Eco2.User" user "User.Eco2")
		(25 "Edge.Cuts" user "Board Geometry/Outline")
		(27 "Margin" user)
		(31 "F.CrtYd" user "Package Geometry/Place Bound Top")
		(29 "B.CrtYd" user "Package Geometry/Place Bound Bottom")
		(35 "F.Fab" user "Ref Des/Assembly Top")
		(33 "B.Fab" user "Ref Des/Assembly Bottom")
	)
	(footprint ""
		(layer "B.Cu")
		(at 456.543918 -316.58306 90)
		(property "Reference" "R943"
			(at 0 0 90)
			(layer "B.SilkS")
			(hide yes)
			(effects
				(font
					(size 1.27 1.27)
				)
				(justify mirror)
			)
		)
		(property "Value" ""
			(at 0 0 90)
			(layer "B.Fab")
			(effects
				(font
					(size 1.27 1.27)
				)
				(justify mirror)
			)
		)
		(duplicate_pad_numbers_are_jumpers no)
		(fp_line
			(start 0.7874 -0.4064)
			(end -0.7874 -0.4064)
			(stroke
				(width 0.1524)
				(type default)
			)
			(layer "B.SilkS")
		)
		(fp_line
			(start -0.7874 -0.4064)
			(end -0.7874 0.4064)
			(stroke
				(width 0.1524)
				(type default)
			)
			(layer "B.SilkS")
		)
		(fp_line
			(start 0.7874 0.4064)
			(end 0.7874 -0.4064)
			(stroke
				(width 0.1524)
				(type default)
			)
			(layer "B.SilkS")
		)
		(fp_line
			(start -0.7874 0.4064)
			(end 0.7874 0.4064)
			(stroke
				(width 0.1524)
				(type default)
			)
			(layer "B.SilkS")
		)
		(fp_line
			(start 0.67945 -0.305054)
			(end 0.12065 -0.305054)
			(stroke
				(width 0.1)
				(type default)
			)
			(layer "B.Fab")
		)
		(fp_line
			(start 0.12065 -0.305054)
			(end 0.12065 -0.2794)
			(stroke
				(width 0.1)
				(type default)
			)
			(layer "B.Fab")
		)
		(fp_line
			(start -0.12065 -0.3048)
			(end -0.67945 -0.3048)
			(stroke
				(width 0.1)
				(type default)
			)
			(layer "B.Fab")
		)
		(fp_line
			(start -0.67945 -0.3048)
			(end -0.67945 0.3048)
			(stroke
				(width 0.1)
				(type default)
			)
			(layer "B.Fab")
		)
		(fp_line
			(start 0.12065 -0.2794)
			(end -0.12065 -0.2794)
			(stroke
				(width 0.1)
				(type default)
			)
			(layer "B.Fab")
		)
		(fp_line
			(start -0.12065 -0.2794)
			(end -0.12065 -0.3048)
			(stroke
				(width 0.1)
				(type default)
			)
			(layer "B.Fab")
		)
		(fp_line
			(start 0.12065 0.2794)
			(end 0.12065 0.3048)
			(stroke
				(width 0.1)
				(type default)
			)
			(layer "B.Fab")
		)
		(fp_line
			(start -0.120396 0.2794)
			(end 0.12065 0.2794)
			(stroke
				(width 0.1)
				(type default)
			)
			(layer "B.Fab")
		)
		(fp_line
			(start 0.67945 0.3048)
			(end 0.67945 -0.305054)
			(stroke
				(width 0.1)
				(type default)
			)
			(layer "B.Fab")
		)
		(fp_line
			(start 0.12065 0.3048)
			(end 0.67945 0.3048)
			(stroke
				(width 0.1)
				(type default)
			)
			(layer "B.Fab")
		)
		(fp_line
			(start -0.120396 0.3048)
			(end -0.120396 0.2794)
			(stroke
				(width 0.1)
				(type default)
			)
			(layer "B.Fab")
		)
		(fp_line
			(start -0.67945 0.3048)
			(end -0.120396 0.3048)
			(stroke
				(width 0.1)
				(type default)
			)
			(layer "B.Fab")
		)
		(pad "1" smd circle
			(at 0.40005 0 270)
			(size 0 0)
			(layers "B.Cu" "B.Mask" "B.Paste")
			(net "P3V3_AUX")
		)
		(pad "2" smd circle
			(at -0.40005 0 270)
			(size 0 0)
			(layers "B.Cu" "B.Mask" "B.Paste")
			(net "PWRGD_FAIL_CPU0_GH_R1")
		)
	)
	(footprint ""
		(layer "B.Cu")
		(at 440.395868 -16.700246)
		(property "Reference" "C1235"
			(at 0 0 0)
			(layer "B.SilkS")
			(hide yes)
			(effects
				(font
					(size 1.27 1.27)
				)
				(justify mirror)
			)
		)
		(property "Value" ""
			(at 0 0 0)
			(layer "B.Fab")
			(effects
				(font
					(size 1.27 1.27)
				)
				(justify mirror)
			)
		)
		(duplicate_pad_numbers_are_jumpers no)
		(fp_line
			(start -0.7874 -0.4064)
			(end -0.7874 0.4064)
			(stroke
				(width 0.1524)
				(type default)
			)
			(layer "B.SilkS")
		)
		(fp_line
			(start -0.7874 0.4064)
			(end 0.7874 0.4064)
			(stroke
				(width 0.1524)
				(type default)
			)
			(layer "B.SilkS")
		)
		(fp_line
			(start 0.7874 -0.4064)
			(end -0.7874 -0.4064)
			(stroke
				(width 0.1524)
				(type default)
			)
			(layer "B.SilkS")
		)
		(fp_line
			(start 0.7874 0.4064)
			(end 0.7874 -0.4064)
			(stroke
				(width 0.1524)
				(type default)
			)
			(layer "B.SilkS")
		)
		(fp_line
			(start -0.67945 -0.3048)
			(end -0.67945 0.3048)
			(stroke
				(width 0.1)
				(type default)
			)
			(layer "B.Fab")
		)
		(fp_line
			(start -0.67945 0.3048)
			(end -0.120396 0.3048)
			(stroke
				(width 0.1)
				(type default)
			)
			(layer "B.Fab")
		)
		(fp_line
			(start -0.12065 -0.3048)
			(end -0.67945 -0.3048)
			(stroke
				(width 0.1)
				(type default)
			)
			(layer "B.Fab")
		)
		(fp_line
			(start -0.12065 -0.2794)
			(end -0.12065 -0.3048)
			(stroke
				(width 0.1)
				(type default)
			)
			(layer "B.Fab")
		)
		(fp_line
			(start -0.120396 0.2794)
			(end 0.12065 0.2794)
			(stroke
				(width 0.1)
				(type default)
			)
			(layer "B.Fab")
		)
		(fp_line
			(start -0.120396 0.3048)
			(end -0.120396 0.2794)
			(stroke
				(width 0.1)
				(type default)
			)
			(layer "B.Fab")
		)
		(fp_line
			(start 0.12065 -0.305054)
			(end 0.12065 -0.2794)
			(stroke
				(width 0.1)
				(type default)
			)
			(layer "B.Fab")
		)
		(fp_line
			(start 0.12065 -0.2794)
			(end -0.12065 -0.2794)
			(stroke
				(width 0.1)
				(type default)
			)
			(layer "B.Fab")
		)
		(fp_line
			(start 0.12065 0.2794)
			(end 0.12065 0.3048)
			(stroke
				(width 0.1)
				(type default)
			)
			(layer "B.Fab")
		)
		(fp_line
			(start 0.12065 0.3048)
			(end 0.67945 0.3048)
			(stroke
				(width 0.1)
				(type default)
			)
			(layer "B.Fab")
		)
		(fp_line
			(start 0.67945 -0.305054)
			(end 0.12065 -0.305054)
			(stroke
				(width 0.1)
				(type default)
			)
			(layer "B.Fab")
		)
		(fp_line
			(start 0.67945 0.3048)
			(end 0.67945 -0.305054)
			(stroke
				(width 0.1)
				(type default)
			)
			(layer "B.Fab")
		)
		(pad "1" smd circle
			(at 0.40005 0 180)
			(size 0 0)
			(layers "B.Cu" "B.Mask" "B.Paste")
			(net "P12V_OCP_SFF")
		)
		(pad "2" smd circle
			(at -0.40005 0 180)
			(size 0 0)
			(layers "B.Cu" "B.Mask" "B.Paste")
			(net "GND")
		)
	)
	(footprint ""
		(layer "B.Cu")
		(at 292.075362 -317.203836 90)
		(property "Reference" "R3878"
			(at 0 0 90)
			(layer "B.SilkS")
			(hide yes)
			(effects
				(font
					(size 1.27 1.27)
				)
				(justify mirror)
			)
		)
		(property "Value" ""
			(at 0 0 90)
			(layer "B.Fab")
			(effects
				(font
					(size 1.27 1.27)
				)
				(justify mirror)
			)
		)
		(duplicate_pad_numbers_are_jumpers no)
		(fp_line
			(start 0.7874 -0.4064)
			(end -0.7874 -0.4064)
			(stroke
				(width 0.1524)
				(type default)
			)
			(layer "B.SilkS")
		)
		(fp_line
			(start -0.7874 -0.4064)
			(end -0.7874 0.4064)
			(stroke
				(width 0.1524)
				(type default)
			)
			(layer "B.SilkS")
		)
		(fp_line
			(start 0.7874 0.4064)
			(end 0.7874 -0.4064)
			(stroke
				(width 0.1524)
				(type default)
			)
			(layer "B.SilkS")
		)
		(fp_line
			(start -0.7874 0.4064)
			(end 0.7874 0.4064)
			(stroke
				(width 0.1524)
				(type default)
			)
			(layer "B.SilkS")
		)
		(fp_line
			(start 0.67945 -0.305054)
			(end 0.12065 -0.305054)
			(stroke
				(width 0.1)
				(type default)
			)
			(layer "B.Fab")
		)
		(fp_line
			(start 0.12065 -0.305054)
			(end 0.12065 -0.2794)
			(stroke
				(width 0.1)
				(type default)
			)
			(layer "B.Fab")
		)
		(fp_line
			(start -0.12065 -0.3048)
			(end -0.67945 -0.3048)
			(stroke
				(width 0.1)
				(type default)
			)
			(layer "B.Fab")
		)
		(fp_line
			(start -0.67945 -0.3048)
			(end -0.67945 0.3048)
			(stroke
				(width 0.1)
				(type default)
			)
			(layer "B.Fab")
		)
		(fp_line
			(start 0.12065 -0.2794)
			(end -0.12065 -0.2794)
			(stroke
				(width 0.1)
				(type default)
			)
			(layer "B.Fab")
		)
		(fp_line
			(start -0.12065 -0.2794)
			(end -0.12065 -0.3048)
			(stroke
				(width 0.1)
				(type default)
			)
			(layer "B.Fab")
		)
		(fp_line
			(start 0.12065 0.2794)
			(end 0.12065 0.3048)
			(stroke
				(width 0.1)
				(type default)
			)
			(layer "B.Fab")
		)
		(fp_line
			(start -0.120396 0.2794)
			(end 0.12065 0.2794)
			(stroke
				(width 0.1)
				(type default)
			)
			(layer "B.Fab")
		)
		(fp_line
			(start 0.67945 0.3048)
			(end 0.67945 -0.305054)
			(stroke
				(width 0.1)
				(type default)
			)
			(layer "B.Fab")
		)
		(fp_line
			(start 0.12065 0.3048)
			(end 0.67945 0.3048)
			(stroke
				(width 0.1)
				(type default)
			)
			(layer "B.Fab")
		)
		(fp_line
			(start -0.120396 0.3048)
			(end -0.120396 0.2794)
			(stroke
				(width 0.1)
				(type default)
			)
			(layer "B.Fab")
		)
		(fp_line
			(start -0.67945 0.3048)
			(end -0.120396 0.3048)
			(stroke
				(width 0.1)
				(type default)
			)
			(layer "B.Fab")
		)
		(pad "1" smd circle
			(at 0.40005 0 270)
			(size 0 0)
			(layers "B.Cu" "B.Mask" "B.Paste")
			(net "I3C_SPD_DDRABCD_CPU0_LVC1_SCL_3")
		)
		(pad "2" smd circle
			(at -0.40005 0 270)
			(size 0 0)
			(layers "B.Cu" "B.Mask" "B.Paste")
			(net "I3C_SPD_DDRABCD_CPU0_LVC1_SCL")
		)
	)
	(footprint ""
		(layer "B.Cu")
		(at 57.517792 -257.918712 -90)
		(property "Reference" "C466"
			(at 0 0 90)
			(layer "B.SilkS")
			(hide yes)
			(effects
				(font
					(size 1.27 1.27)
				)
				(justify mirror)
			)
		)
		(property "Value" ""
			(at 0 0 90)
			(layer "B.Fab")
			(effects
				(font
					(size 1.27 1.27)
				)
				(justify mirror)
			)
		)
		(duplicate_pad_numbers_are_jumpers no)
		(fp_line
			(start -1.524 0.762)
			(end 1.524 0.762)
			(stroke
				(width 0.1524)
				(type default)
			)
			(layer "B.SilkS")
		)
		(fp_line
			(start 1.524 0.762)
			(end 1.524 -0.762)
			(stroke
				(width 0.1524)
				(type default)
			)
			(layer "B.SilkS")
		)
		(fp_line
			(start -1.524 -0.762)
			(end -1.524 0.762)
			(stroke
				(width 0.1524)
				(type default)
			)
			(layer "B.SilkS")
		)
		(fp_line
			(start 1.524 -0.762)
			(end -1.524 -0.762)
			(stroke
				(width 0.1524)
				(type default)
			)
			(layer "B.SilkS")
		)
		(fp_line
			(start -1.1049 0.724916)
			(end -1.1049 -0.724916)
			(stroke
				(width 0.1)
				(type default)
			)
			(layer "B.Fab")
		)
		(fp_line
			(start 1.1049 0.724916)
			(end -1.1049 0.724916)
			(stroke
				(width 0.1)
				(type default)
			)
			(layer "B.Fab")
		)
		(fp_line
			(start -1.1049 -0.724916)
			(end 1.1049 -0.724916)
			(stroke
				(width 0.1)
				(type default)
			)
			(layer "B.Fab")
		)
		(fp_line
			(start 1.1049 -0.724916)
			(end 1.1049 0.724916)
			(stroke
				(width 0.1)
				(type default)
			)
			(layer "B.Fab")
		)
		(pad "1" smd rect
			(at 0.889 0 270)
			(size 1.016 1.27)
			(layers "B.Cu" "B.Mask" "B.Paste")
			(net "PVCCFA_EHV_FIVRA_CPU1")
		)
		(pad "2" smd rect
			(at -0.889 0 270)
			(size 1.016 1.27)
			(layers "B.Cu" "B.Mask" "B.Paste")
			(net "GND")
		)
	)
	(footprint ""
		(layer "B.Cu")
		(at 236.20095 -51.209448)
		(property "Reference" "R2296"
			(at 0 0 0)
			(layer "B.SilkS")
			(hide yes)
			(effects
				(font
					(size 1.27 1.27)
				)
				(justify mirror)
			)
		)
		(property "Value" ""
			(at 0 0 0)
			(layer "B.Fab")
			(effects
				(font
					(size 1.27 1.27)
				)
				(justify mirror)
			)
		)
		(duplicate_pad_numbers_are_jumpers no)
		(fp_line
			(start -0.7874 -0.4064)
			(end -0.7874 0.4064)
			(stroke
				(width 0.1524)
				(type default)
			)
			(layer "B.SilkS")
		)
		(fp_line
			(start -0.7874 0.4064)
			(end 0.7874 0.4064)
			(stroke
				(width 0.1524)
				(type default)
			)
			(layer "B.SilkS")
		)
		(fp_line
			(start 0.7874 -0.4064)
			(end -0.7874 -0.4064)
			(stroke
				(width 0.1524)
				(type default)
			)
			(layer "B.SilkS")
		)
		(fp_line
			(start 0.7874 0.4064)
			(end 0.7874 -0.4064)
			(stroke
				(width 0.1524)
				(type default)
			)
			(layer "B.SilkS")
		)
		(fp_line
			(start -0.67945 -0.3048)
			(end -0.67945 0.3048)
			(stroke
				(width 0.1)
				(type default)
			)
			(layer "B.Fab")
		)
		(fp_line
			(start -0.67945 0.3048)
			(end -0.120396 0.3048)
			(stroke
				(width 0.1)
				(type default)
			)
			(layer "B.Fab")
		)
		(fp_line
			(start -0.12065 -0.3048)
			(end -0.67945 -0.3048)
			(stroke
				(width 0.1)
				(type default)
			)
			(layer "B.Fab")
		)
		(fp_line
			(start -0.12065 -0.2794)
			(end -0.12065 -0.3048)
			(stroke
				(width 0.1)
				(type default)
			)
			(layer "B.Fab")
		)
		(fp_line
			(start -0.120396 0.2794)
			(end 0.12065 0.2794)
			(stroke
				(width 0.1)
				(type default)
			)
			(layer "B.Fab")
		)
		(fp_line
			(start -0.120396 0.3048)
			(end -0.120396 0.2794)
			(stroke
				(width 0.1)
				(type default)
			)
			(layer "B.Fab")
		)
		(fp_line
			(start 0.12065 -0.305054)
			(end 0.12065 -0.2794)
			(stroke
				(width 0.1)
				(type default)
			)
			(layer "B.Fab")
		)
		(fp_line
			(start 0.12065 -0.2794)
			(end -0.12065 -0.2794)
			(stroke
				(width 0.1)
				(type default)
			)
			(layer "B.Fab")
		)
		(fp_line
			(start 0.12065 0.2794)
			(end 0.12065 0.3048)
			(stroke
				(width 0.1)
				(type default)
			)
			(layer "B.Fab")
		)
		(fp_line
			(start 0.12065 0.3048)
			(end 0.67945 0.3048)
			(stroke
				(width 0.1)
				(type default)
			)
			(layer "B.Fab")
		)
		(fp_line
			(start 0.67945 -0.305054)
			(end 0.12065 -0.305054)
			(stroke
				(width 0.1)
				(type default)
			)
			(layer "B.Fab")
		)
		(fp_line
			(start 0.67945 0.3048)
			(end 0.67945 -0.305054)
			(stroke
				(width 0.1)
				(type default)
			)
			(layer "B.Fab")
		)
		(pad "1" smd circle
			(at 0.40005 0 180)
			(size 0 0)
			(layers "B.Cu" "B.Mask" "B.Paste")
			(net "E1S_0_PWRDIS")
		)
		(pad "2" smd circle
			(at -0.40005 0 180)
			(size 0 0)
			(layers "B.Cu" "B.Mask" "B.Paste")
			(net "GND")
		)
	)
	(footprint ""
		(layer "B.Cu")
		(at 23.145242 -316.36589 90)
		(property "Reference" "R3895"
			(at 0 0 90)
			(layer "B.SilkS")
			(hide yes)
			(effects
				(font
					(size 1.27 1.27)
				)
				(justify mirror)
			)
		)
		(property "Value" ""
			(at 0 0 90)
			(layer "B.Fab")
			(effects
				(font
					(size 1.27 1.27)
				)
				(justify mirror)
			)
		)
		(duplicate_pad_numbers_are_jumpers no)
		(fp_line
			(start 0.7874 -0.4064)
			(end -0.7874 -0.4064)
			(stroke
				(width 0.1524)
				(type default)
			)
			(layer "B.SilkS")
		)
		(fp_line
			(start -0.7874 -0.4064)
			(end -0.7874 0.4064)
			(stroke
				(width 0.1524)
				(type default)
			)
			(layer "B.SilkS")
		)
		(fp_line
			(start 0.7874 0.4064)
			(end 0.7874 -0.4064)
			(stroke
				(width 0.1524)
				(type default)
			)
			(layer "B.SilkS")
		)
		(fp_line
			(start -0.7874 0.4064)
			(end 0.7874 0.4064)
			(stroke
				(width 0.1524)
				(type default)
			)
			(layer "B.SilkS")
		)
		(fp_line
			(start 0.67945 -0.305054)
			(end 0.12065 -0.305054)
			(stroke
				(width 0.1)
				(type default)
			)
			(layer "B.Fab")
		)
		(fp_line
			(start 0.12065 -0.305054)
			(end 0.12065 -0.2794)
			(stroke
				(width 0.1)
				(type default)
			)
			(layer "B.Fab")
		)
		(fp_line
			(start -0.12065 -0.3048)
			(end -0.67945 -0.3048)
			(stroke
				(width 0.1)
				(type default)
			)
			(layer "B.Fab")
		)
		(fp_line
			(start -0.67945 -0.3048)
			(end -0.67945 0.3048)
			(stroke
				(width 0.1)
				(type default)
			)
			(layer "B.Fab")
		)
		(fp_line
			(start 0.12065 -0.2794)
			(end -0.12065 -0.2794)
			(stroke
				(width 0.1)
				(type default)
			)
			(layer "B.Fab")
		)
		(fp_line
			(start -0.12065 -0.2794)
			(end -0.12065 -0.3048)
			(stroke
				(width 0.1)
				(type default)
			)
			(layer "B.Fab")
		)
		(fp_line
			(start 0.12065 0.2794)
			(end 0.12065 0.3048)
			(stroke
				(width 0.1)
				(type default)
			)
			(layer "B.Fab")
		)
		(fp_line
			(start -0.120396 0.2794)
			(end 0.12065 0.2794)
			(stroke
				(width 0.1)
				(type default)
			)
			(layer "B.Fab")
		)
		(fp_line
			(start 0.67945 0.3048)
			(end 0.67945 -0.305054)
			(stroke
				(width 0.1)
				(type default)
			)
			(layer "B.Fab")
		)
		(fp_line
			(start 0.12065 0.3048)
			(end 0.67945 0.3048)
			(stroke
				(width 0.1)
				(type default)
			)
			(layer "B.Fab")
		)
		(fp_line
			(start -0.120396 0.3048)
			(end -0.120396 0.2794)
			(stroke
				(width 0.1)
				(type default)
			)
			(layer "B.Fab")
		)
		(fp_line
			(start -0.67945 0.3048)
			(end -0.120396 0.3048)
			(stroke
				(width 0.1)
				(type default)
			)
			(layer "B.Fab")
		)
		(pad "1" smd circle
			(at 0.40005 0 270)
			(size 0 0)
			(layers "B.Cu" "B.Mask" "B.Paste")
			(net "I3C_SPD_DDRABCD_CPU1_LVC1_SCL_4")
		)
		(pad "2" smd circle
			(at -0.40005 0 270)
			(size 0 0)
			(layers "B.Cu" "B.Mask" "B.Paste")
			(net "I3C_SPD_DDRABCD_CPU1_LVC1_SCL")
		)
	)
	(footprint ""
		(layer "B.Cu")
		(at 350.435418 -296.054526 180)
		(property "Reference" "C386"
			(at 0 0 0)
			(layer "B.SilkS")
			(hide yes)
			(effects
				(font
					(size 1.27 1.27)
				)
				(justify mirror)
			)
		)
		(property "Value" ""
			(at 0 0 0)
			(layer "B.Fab")
			(effects
				(font
					(size 1.27 1.27)
				)
				(justify mirror)
			)
		)
		(duplicate_pad_numbers_are_jumpers no)
		(fp_line
			(start 1.524 0.762)
			(end 1.524 -0.762)
			(stroke
				(width 0.1524)
				(type default)
			)
			(layer "B.SilkS")
		)
		(fp_line
			(start 1.524 -0.762)
			(end -1.524 -0.762)
			(stroke
				(width 0.1524)
				(type default)
			)
			(layer "B.SilkS")
		)
		(fp_line
			(start -1.524 0.762)
			(end 1.524 0.762)
			(stroke
				(width 0.1524)
				(type default)
			)
			(layer "B.SilkS")
		)
		(fp_line
			(start -1.524 -0.762)
			(end -1.524 0.762)
			(stroke
				(width 0.1524)
				(type default)
			)
			(layer "B.SilkS")
		)
		(fp_line
			(start 1.1049 0.724916)
			(end -1.1049 0.724916)
			(stroke
				(width 0.1)
				(type default)
			)
			(layer "B.Fab")
		)
		(fp_line
			(start 1.1049 -0.724916)
			(end 1.1049 0.724916)
			(stroke
				(width 0.1)
				(type default)
			)
			(layer "B.Fab")
		)
		(fp_line
			(start -1.1049 0.724916)
			(end -1.1049 -0.724916)
			(stroke
				(width 0.1)
				(type default)
			)
			(layer "B.Fab")
		)
		(fp_line
			(start -1.1049 -0.724916)
			(end 1.1049 -0.724916)
			(stroke
				(width 0.1)
				(type default)
			)
			(layer "B.Fab")
		)
		(pad "1" smd rect
			(at 0.889 0 180)
			(size 1.016 1.27)
			(layers "B.Cu" "B.Mask" "B.Paste")
			(net "PVCCIN_CPU0")
		)
		(pad "2" smd rect
			(at -0.889 0 180)
			(size 1.016 1.27)
			(layers "B.Cu" "B.Mask" "B.Paste")
			(net "GND")
		)
	)
)
